(kicad_pcb
	(version 20260206)
	(generator "pcbnew")
	(generator_version "10.0")
	(general
		(thickness 1.6)
		(legacy_teardrops no)
	)
	(paper "A4")
	(title_block
		(title "Bryce Canyon_IOM_IOC_16318-2_OCP.brd")
		(comment 1 "Bryce Canyon / footprints 584-591 of 1605")
	)
	(layers
		(0 "F.Cu" signal "TOP")
		(4 "In1.Cu" signal "L2GND")
		(6 "In2.Cu" signal "L3")
		(8 "In3.Cu" signal "L4VCC")
		(10 "In4.Cu" signal "L5VCC")
		(12 "In5.Cu" signal "L6")
		(14 "In6.Cu" signal "L7GND")
		(2 "B.Cu" signal "BOTTOM")
		(9 "F.Adhes" user "F.Adhesive")
		(11 "B.Adhes" user "B.Adhesive")
		(13 "F.Paste" user "Package Geometry/Pastemask Top")
		(15 "B.Paste" user "Package Geometry/Pastemask Bottom")
		(5 "F.SilkS" user "Ref Des/Silkscreen Top")
		(7 "B.SilkS" user "Ref Des/Silkscreen Bottom")
		(1 "F.Mask" user "Board Geometry/Soldermask Top")
		(3 "B.Mask" user "Board Geometry/Soldermask Bottom")
		(17 "Dwgs.User" user "User.Drawings")
		(19 "Cmts.User" user "User.Comments")
		(21 "Eco1.User" user "User.Eco1")
		(23 "Eco2.User" user "User.Eco2")
		(25 "Edge.Cuts" user "Board Geometry/Outline")
		(27 "Margin" user)
		(31 "F.CrtYd" user "Package Geometry/Place Bound Top")
		(29 "B.CrtYd" user "Package Geometry/Place Bound Bottom")
		(35 "F.Fab" user "Ref Des/Assembly Top")
		(33 "B.Fab" user "Ref Des/Assembly Bottom")
	)
	(footprint ""
		(layer "F.Cu")
		(at 37.5412 -161.4424)
		(property "Reference" "R300"
			(at 0 0 0)
			(layer "F.SilkS")
			(hide yes)
			(effects
				(font
					(size 1.27 1.27)
				)
			)
		)
		(property "Value" "4K7R2F-GP"
			(at 0.064008 -3.993896 0)
			(unlocked yes)
			(layer "F.Fab")
			(hide yes)
			(effects
				(font
					(size 1.016 1.016)
					(thickness 0.1524)
				)
			)
		)
		(property "Device Type" "R402H16"
			(at 0.064008 -5.517896 0)
			(unlocked yes)
			(layer "F.Fab")
			(hide yes)
			(effects
				(font
					(size 1.016 1.016)
					(thickness 0.1524)
				)
			)
		)
		(duplicate_pad_numbers_are_jumpers no)
		(fp_line
			(start -0.508 -0.9398)
			(end -0.508 0.9398)
			(stroke
				(width 0.1524)
				(type default)
			)
			(layer "F.SilkS")
		)
		(fp_line
			(start 0.508 -0.9398)
			(end -0.508 -0.9398)
			(stroke
				(width 0.1524)
				(type default)
			)
			(layer "F.SilkS")
		)
		(fp_rect
			(start -0.508 0.9398)
			(end 0.508 -0.9398)
			(stroke
				(width 0)
				(type default)
			)
			(fill no)
			(layer "F.CrtYd")
		)
		(fp_rect
			(start -0.508 0.9398)
			(end 0.508 -0.9398)
			(stroke
				(width 0)
				(type default)
			)
			(fill no)
			(layer "F.Fab")
		)
		(pad "1" smd custom
			(at 0 -0.4445)
			(size 0.1397 0.1397)
			(layers "F.Cu" "F.Mask" "F.Paste")
			(net "P3V3_STBY")
			(options
				(clearance outline)
				(anchor circle)
			)
			(primitives
				(gr_poly
					(pts
						(arc
							(start -0.1778 -0.2794)
							(mid -0.249642 -0.249642)
							(end -0.2794 -0.1778)
						)
						(arc
							(start -0.2794 0.1778)
							(mid -0.249642 0.249642)
							(end -0.1778 0.2794)
						)
						(arc
							(start 0.1778 0.2794)
							(mid 0.249642 0.249642)
							(end 0.2794 0.1778)
						)
						(arc
							(start 0.2794 -0.1778)
							(mid 0.249642 -0.249642)
							(end 0.1778 -0.2794)
						)
					)
					(width 0)
					(fill yes)
				)
			)
		)
		(pad "2" smd custom
			(at 0 0.4445)
			(size 0.1397 0.1397)
			(layers "F.Cu" "F.Mask" "F.Paste")
			(net "UART_COMP_OUT_TX")
			(options
				(clearance outline)
				(anchor circle)
			)
			(primitives
				(gr_poly
					(pts
						(arc
							(start -0.1778 -0.2794)
							(mid -0.249642 -0.249642)
							(end -0.2794 -0.1778)
						)
						(arc
							(start -0.2794 0.1778)
							(mid -0.249642 0.249642)
							(end -0.1778 0.2794)
						)
						(arc
							(start 0.1778 0.2794)
							(mid 0.249642 0.249642)
							(end 0.2794 0.1778)
						)
						(arc
							(start 0.2794 -0.1778)
							(mid 0.249642 -0.249642)
							(end 0.1778 -0.2794)
						)
					)
					(width 0)
					(fill yes)
				)
			)
		)
	)
	(footprint ""
		(layer "F.Cu")
		(at 86.846918 -58.713624 90)
		(property "Reference" "R4"
			(at 0 0 90)
			(layer "F.SilkS")
			(hide yes)
			(effects
				(font
					(size 1.27 1.27)
				)
			)
		)
		(property "Value" "0R2J-2-GP"
			(at 0.064008 -3.993896 90)
			(unlocked yes)
			(layer "F.Fab")
			(hide yes)
			(effects
				(font
					(size 1.016 1.016)
					(thickness 0.1524)
				)
			)
		)
		(property "Device Type" "R402H16"
			(at 0.064008 -5.517896 90)
			(unlocked yes)
			(layer "F.Fab")
			(hide yes)
			(effects
				(font
					(size 1.016 1.016)
					(thickness 0.1524)
				)
			)
		)
		(duplicate_pad_numbers_are_jumpers no)
		(fp_line
			(start 0.508 -0.9398)
			(end -0.508 -0.9398)
			(stroke
				(width 0.1524)
				(type default)
			)
			(layer "F.SilkS")
		)
		(fp_line
			(start -0.508 -0.9398)
			(end -0.508 0.9398)
			(stroke
				(width 0.1524)
				(type default)
			)
			(layer "F.SilkS")
		)
		(fp_rect
			(start -0.508 0.9398)
			(end 0.508 -0.9398)
			(stroke
				(width 0)
				(type default)
			)
			(fill no)
			(layer "F.CrtYd")
		)
		(fp_rect
			(start -0.508 0.9398)
			(end 0.508 -0.9398)
			(stroke
				(width 0)
				(type default)
			)
			(fill no)
			(layer "F.Fab")
		)
		(pad "1" smd custom
			(at 0 -0.4445 90)
			(size 0.1397 0.1397)
			(layers "F.Cu" "F.Mask" "F.Paste")
			(net "I2C_MEZZ_ALERT_R_N")
			(options
				(clearance outline)
				(anchor circle)
			)
			(primitives
				(gr_poly
					(pts
						(arc
							(start -0.1778 -0.2794)
							(mid -0.249642 -0.249642)
							(end -0.2794 -0.1778)
						)
						(arc
							(start -0.2794 0.1778)
							(mid -0.249642 0.249642)
							(end -0.1778 0.2794)
						)
						(arc
							(start 0.1778 0.2794)
							(mid 0.249642 0.249642)
							(end 0.2794 0.1778)
						)
						(arc
							(start 0.2794 -0.1778)
							(mid 0.249642 -0.249642)
							(end 0.1778 -0.2794)
						)
					)
					(width 0)
					(fill yes)
				)
			)
		)
		(pad "2" smd custom
			(at 0 0.4445 90)
			(size 0.1397 0.1397)
			(layers "F.Cu" "F.Mask" "F.Paste")
			(net "I2C_MEZZ_ALERT_N")
			(options
				(clearance outline)
				(anchor circle)
			)
			(primitives
				(gr_poly
					(pts
						(arc
							(start -0.1778 -0.2794)
							(mid -0.249642 -0.249642)
							(end -0.2794 -0.1778)
						)
						(arc
							(start -0.2794 0.1778)
							(mid -0.249642 0.249642)
							(end -0.1778 0.2794)
						)
						(arc
							(start 0.1778 0.2794)
							(mid 0.249642 0.249642)
							(end 0.2794 0.1778)
						)
						(arc
							(start 0.2794 -0.1778)
							(mid 0.249642 -0.249642)
							(end 0.1778 -0.2794)
						)
					)
					(width 0)
					(fill yes)
				)
			)
		)
	)
	(footprint ""
		(layer "F.Cu")
		(at 56.3626 -158.8516)
		(property "Reference" "R395"
			(at 0 0 0)
			(layer "F.SilkS")
			(hide yes)
			(effects
				(font
					(size 1.27 1.27)
				)
			)
		)
		(property "Value" "4K7R2F-GP"
			(at 0.064008 -3.993896 0)
			(unlocked yes)
			(layer "F.Fab")
			(hide yes)
			(effects
				(font
					(size 1.016 1.016)
					(thickness 0.1524)
				)
			)
		)
		(property "Device Type" "R402H16"
			(at 0.064008 -5.517896 0)
			(unlocked yes)
			(layer "F.Fab")
			(hide yes)
			(effects
				(font
					(size 1.016 1.016)
					(thickness 0.1524)
				)
			)
		)
		(duplicate_pad_numbers_are_jumpers no)
		(fp_line
			(start -0.508 -0.9398)
			(end -0.508 0.9398)
			(stroke
				(width 0.1524)
				(type default)
			)
			(layer "F.SilkS")
		)
		(fp_line
			(start 0.508 -0.9398)
			(end -0.508 -0.9398)
			(stroke
				(width 0.1524)
				(type default)
			)
			(layer "F.SilkS")
		)
		(fp_rect
			(start -0.508 0.9398)
			(end 0.508 -0.9398)
			(stroke
				(width 0)
				(type default)
			)
			(fill no)
			(layer "F.CrtYd")
		)
		(fp_rect
			(start -0.508 0.9398)
			(end 0.508 -0.9398)
			(stroke
				(width 0)
				(type default)
			)
			(fill no)
			(layer "F.Fab")
		)
		(pad "1" smd custom
			(at 0 -0.4445)
			(size 0.1397 0.1397)
			(layers "F.Cu" "F.Mask" "F.Paste")
			(net "GND")
			(options
				(clearance outline)
				(anchor circle)
			)
			(primitives
				(gr_poly
					(pts
						(arc
							(start -0.1778 -0.2794)
							(mid -0.249642 -0.249642)
							(end -0.2794 -0.1778)
						)
						(arc
							(start -0.2794 0.1778)
							(mid -0.249642 0.249642)
							(end -0.1778 0.2794)
						)
						(arc
							(start 0.1778 0.2794)
							(mid 0.249642 0.249642)
							(end 0.2794 0.1778)
						)
						(arc
							(start 0.2794 -0.1778)
							(mid 0.249642 -0.249642)
							(end 0.1778 -0.2794)
						)
					)
					(width 0)
					(fill yes)
				)
			)
		)
		(pad "2" smd custom
			(at 0 0.4445)
			(size 0.1397 0.1397)
			(layers "F.Cu" "F.Mask" "F.Paste")
			(net "MAC2_TXCTL")
			(options
				(clearance outline)
				(anchor circle)
			)
			(primitives
				(gr_poly
					(pts
						(arc
							(start -0.1778 -0.2794)
							(mid -0.249642 -0.249642)
							(end -0.2794 -0.1778)
						)
						(arc
							(start -0.2794 0.1778)
							(mid -0.249642 0.249642)
							(end -0.1778 0.2794)
						)
						(arc
							(start 0.1778 0.2794)
							(mid 0.249642 0.249642)
							(end 0.2794 0.1778)
						)
						(arc
							(start 0.2794 -0.1778)
							(mid 0.249642 -0.249642)
							(end 0.1778 -0.2794)
						)
					)
					(width 0)
					(fill yes)
				)
			)
		)
	)
	(footprint ""
		(layer "F.Cu")
		(at 63.9826 -172.212 180)
		(property "Reference" "R71"
			(at 0 0 180)
			(layer "F.SilkS")
			(hide yes)
			(effects
				(font
					(size 1.27 1.27)
				)
			)
		)
		(property "Value" "4K75R2F-1-GP"
			(at 0.064008 -3.993896 180)
			(unlocked yes)
			(layer "F.Fab")
			(hide yes)
			(effects
				(font
					(size 1.016 1.016)
					(thickness 0.1524)
				)
			)
		)
		(property "Device Type" "R402H16"
			(at 0.064008 -5.517896 180)
			(unlocked yes)
			(layer "F.Fab")
			(hide yes)
			(effects
				(font
					(size 1.016 1.016)
					(thickness 0.1524)
				)
			)
		)
		(duplicate_pad_numbers_are_jumpers no)
		(fp_line
			(start 0.508 -0.9398)
			(end -0.508 -0.9398)
			(stroke
				(width 0.1524)
				(type default)
			)
			(layer "F.SilkS")
		)
		(fp_line
			(start -0.508 -0.9398)
			(end -0.508 0.9398)
			(stroke
				(width 0.1524)
				(type default)
			)
			(layer "F.SilkS")
		)
		(fp_rect
			(start -0.508 0.9398)
			(end 0.508 -0.9398)
			(stroke
				(width 0)
				(type default)
			)
			(fill no)
			(layer "F.CrtYd")
		)
		(fp_rect
			(start -0.508 0.9398)
			(end 0.508 -0.9398)
			(stroke
				(width 0)
				(type default)
			)
			(fill no)
			(layer "F.Fab")
		)
		(pad "1" smd custom
			(at 0 -0.4445 180)
			(size 0.1397 0.1397)
			(layers "F.Cu" "F.Mask" "F.Paste")
			(net "P3V3_STBY")
			(options
				(clearance outline)
				(anchor circle)
			)
			(primitives
				(gr_poly
					(pts
						(arc
							(start -0.1778 -0.2794)
							(mid -0.249642 -0.249642)
							(end -0.2794 -0.1778)
						)
						(arc
							(start -0.2794 0.1778)
							(mid -0.249642 0.249642)
							(end -0.1778 0.2794)
						)
						(arc
							(start 0.1778 0.2794)
							(mid 0.249642 0.249642)
							(end 0.2794 0.1778)
						)
						(arc
							(start 0.2794 -0.1778)
							(mid 0.249642 -0.249642)
							(end 0.1778 -0.2794)
						)
					)
					(width 0)
					(fill yes)
				)
			)
		)
		(pad "2" smd custom
			(at 0 0.4445 180)
			(size 0.1397 0.1397)
			(layers "F.Cu" "F.Mask" "F.Paste")
			(net "FM_TPM_PRSNT_RST_N_C")
			(options
				(clearance outline)
				(anchor circle)
			)
			(primitives
				(gr_poly
					(pts
						(arc
							(start -0.1778 -0.2794)
							(mid -0.249642 -0.249642)
							(end -0.2794 -0.1778)
						)
						(arc
							(start -0.2794 0.1778)
							(mid -0.249642 0.249642)
							(end -0.1778 0.2794)
						)
						(arc
							(start 0.1778 0.2794)
							(mid 0.249642 0.249642)
							(end 0.2794 0.1778)
						)
						(arc
							(start 0.2794 -0.1778)
							(mid 0.249642 -0.249642)
							(end 0.1778 -0.2794)
						)
					)
					(width 0)
					(fill yes)
				)
			)
		)
	)
	(footprint ""
		(layer "F.Cu")
		(at 124.841 -7.62 -90)
		(property "Reference" "R438"
			(at 0 0 270)
			(layer "F.SilkS")
			(hide yes)
			(effects
				(font
					(size 1.27 1.27)
				)
			)
		)
		(property "Value" "10KR2J-3-GP"
			(at 0.064008 -3.993896 270)
			(unlocked yes)
			(layer "F.Fab")
			(hide yes)
			(effects
				(font
					(size 1.016 1.016)
					(thickness 0.1524)
				)
			)
		)
		(property "Device Type" "R402H16"
			(at 0.064008 -5.517896 270)
			(unlocked yes)
			(layer "F.Fab")
			(hide yes)
			(effects
				(font
					(size 1.016 1.016)
					(thickness 0.1524)
				)
			)
		)
		(duplicate_pad_numbers_are_jumpers no)
		(fp_line
			(start -0.508 -0.9398)
			(end -0.508 0.9398)
			(stroke
				(width 0.1524)
				(type default)
			)
			(layer "F.SilkS")
		)
		(fp_line
			(start 0.508 -0.9398)
			(end -0.508 -0.9398)
			(stroke
				(width 0.1524)
				(type default)
			)
			(layer "F.SilkS")
		)
		(fp_rect
			(start -0.508 0.9398)
			(end 0.508 -0.9398)
			(stroke
				(width 0)
				(type default)
			)
			(fill no)
			(layer "F.CrtYd")
		)
		(fp_rect
			(start -0.508 0.9398)
			(end 0.508 -0.9398)
			(stroke
				(width 0)
				(type default)
			)
			(fill no)
			(layer "F.Fab")
		)
		(pad "1" smd custom
			(at 0 -0.4445 270)
			(size 0.1397 0.1397)
			(layers "F.Cu" "F.Mask" "F.Paste")
			(net "GND")
			(options
				(clearance outline)
				(anchor circle)
			)
			(primitives
				(gr_poly
					(pts
						(arc
							(start -0.1778 -0.2794)
							(mid -0.249642 -0.249642)
							(end -0.2794 -0.1778)
						)
						(arc
							(start -0.2794 0.1778)
							(mid -0.249642 0.249642)
							(end -0.1778 0.2794)
						)
						(arc
							(start 0.1778 0.2794)
							(mid 0.249642 0.249642)
							(end 0.2794 0.1778)
						)
						(arc
							(start 0.2794 -0.1778)
							(mid 0.249642 -0.249642)
							(end 0.1778 -0.2794)
						)
					)
					(width 0)
					(fill yes)
				)
			)
		)
		(pad "2" smd custom
			(at 0 0.4445 270)
			(size 0.1397 0.1397)
			(layers "F.Cu" "F.Mask" "F.Paste")
			(net "MB0_RETRY_R")
			(options
				(clearance outline)
				(anchor circle)
			)
			(primitives
				(gr_poly
					(pts
						(arc
							(start -0.1778 -0.2794)
							(mid -0.249642 -0.249642)
							(end -0.2794 -0.1778)
						)
						(arc
							(start -0.2794 0.1778)
							(mid -0.249642 0.249642)
							(end -0.1778 0.2794)
						)
						(arc
							(start 0.1778 0.2794)
							(mid 0.249642 0.249642)
							(end 0.2794 0.1778)
						)
						(arc
							(start 0.2794 -0.1778)
							(mid 0.249642 -0.249642)
							(end 0.1778 -0.2794)
						)
					)
					(width 0)
					(fill yes)
				)
			)
		)
	)
	(footprint ""
		(layer "F.Cu")
		(at 156.464 -117.602 180)
		(property "Reference" "G4"
			(at 0 0 180)
			(layer "F.SilkS")
			(hide yes)
			(effects
				(font
					(size 1.27 1.27)
				)
			)
		)
		(property "Value" "GAP-CLOSE-PWR-4-GP"
			(at -2.4638 -0.5461 180)
			(unlocked yes)
			(layer "F.Fab")
			(hide yes)
			(effects
				(font
					(size 1.016 1.016)
					(thickness 0.1524)
				)
			)
		)
		(property "Device Type" "GAP-CLOSE-PWR-4"
			(at -2.4638 -2.0701 180)
			(unlocked yes)
			(layer "F.Fab")
			(hide yes)
			(effects
				(font
					(size 1.016 1.016)
					(thickness 0.1524)
				)
			)
		)
		(duplicate_pad_numbers_are_jumpers no)
		(fp_rect
			(start -0.2794 0.254)
			(end 0.2794 -0.254)
			(stroke
				(width 0)
				(type default)
			)
			(fill no)
			(layer "F.CrtYd")
		)
		(fp_rect
			(start -0.2794 0.254)
			(end 0.2794 -0.254)
			(stroke
				(width 0)
				(type default)
			)
			(fill no)
			(layer "F.Fab")
		)
		(pad "1" smd rect
			(at -0.0635 0 180)
			(size 0.1778 0.254)
			(layers "F.Cu" "F.Mask" "F.Paste")
			(net "P1V8_STBY")
		)
		(pad "2" smd rect
			(at 0.0635 0 180)
			(size 0.1778 0.254)
			(layers "F.Cu" "F.Mask" "F.Paste")
			(net "P1V8_STBY_CC")
		)
	)
	(footprint ""
		(layer "F.Cu")
		(at 153.926032 -94.852998 90)
		(property "Reference" "R638"
			(at 0 0 90)
			(layer "F.SilkS")
			(hide yes)
			(effects
				(font
					(size 1.27 1.27)
				)
			)
		)
		(property "Value" "4K7R2F-GP"
			(at 0.064008 -3.993896 90)
			(unlocked yes)
			(layer "F.Fab")
			(hide yes)
			(effects
				(font
					(size 1.016 1.016)
					(thickness 0.1524)
				)
			)
		)
		(property "Device Type" "R402H16"
			(at 0.064008 -5.517896 90)
			(unlocked yes)
			(layer "F.Fab")
			(hide yes)
			(effects
				(font
					(size 1.016 1.016)
					(thickness 0.1524)
				)
			)
		)
		(duplicate_pad_numbers_are_jumpers no)
		(fp_line
			(start 0.508 -0.9398)
			(end -0.508 -0.9398)
			(stroke
				(width 0.1524)
				(type default)
			)
			(layer "F.SilkS")
		)
		(fp_line
			(start -0.508 -0.9398)
			(end -0.508 0.9398)
			(stroke
				(width 0.1524)
				(type default)
			)
			(layer "F.SilkS")
		)
		(fp_rect
			(start -0.508 0.9398)
			(end 0.508 -0.9398)
			(stroke
				(width 0)
				(type default)
			)
			(fill no)
			(layer "F.CrtYd")
		)
		(fp_rect
			(start -0.508 0.9398)
			(end 0.508 -0.9398)
			(stroke
				(width 0)
				(type default)
			)
			(fill no)
			(layer "F.Fab")
		)
		(pad "1" smd custom
			(at 0 -0.4445 90)
			(size 0.1397 0.1397)
			(layers "F.Cu" "F.Mask" "F.Paste")
			(net "SYS_RST_N_0")
			(options
				(clearance outline)
				(anchor circle)
			)
			(primitives
				(gr_poly
					(pts
						(arc
							(start -0.1778 -0.2794)
							(mid -0.249642 -0.249642)
							(end -0.2794 -0.1778)
						)
						(arc
							(start -0.2794 0.1778)
							(mid -0.249642 0.249642)
							(end -0.1778 0.2794)
						)
						(arc
							(start 0.1778 0.2794)
							(mid 0.249642 0.249642)
							(end 0.2794 0.1778)
						)
						(arc
							(start 0.2794 -0.1778)
							(mid 0.249642 -0.249642)
							(end 0.1778 -0.2794)
						)
					)
					(width 0)
					(fill yes)
				)
			)
		)
		(pad "2" smd custom
			(at 0 0.4445 90)
			(size 0.1397 0.1397)
			(layers "F.Cu" "F.Mask" "F.Paste")
			(net "P1V8")
			(options
				(clearance outline)
				(anchor circle)
			)
			(primitives
				(gr_poly
					(pts
						(arc
							(start -0.1778 -0.2794)
							(mid -0.249642 -0.249642)
							(end -0.2794 -0.1778)
						)
						(arc
							(start -0.2794 0.1778)
							(mid -0.249642 0.249642)
							(end -0.1778 0.2794)
						)
						(arc
							(start 0.1778 0.2794)
							(mid 0.249642 0.249642)
							(end 0.2794 0.1778)
						)
						(arc
							(start 0.2794 -0.1778)
							(mid 0.249642 -0.249642)
							(end 0.1778 -0.2794)
						)
					)
					(width 0)
					(fill yes)
				)
			)
		)
	)
	(footprint ""
		(layer "F.Cu")
		(at 16.023336 -163.5506 -90)
		(property "Reference" "C222"
			(at 0 0 270)
			(layer "F.SilkS")
			(hide yes)
			(effects
				(font
					(size 1.27 1.27)
				)
			)
		)
		(property "Value" "SC1KP50V2KX-1GP"
			(at 1.1811 -2.7051 270)
			(unlocked yes)
			(layer "F.Fab")
			(hide yes)
			(effects
				(font
					(size 1.016 1.016)
					(thickness 0.1524)
				)
			)
		)
		(property "Device Type" "C402H22"
			(at 1.1811 -4.2291 270)
			(unlocked yes)
			(layer "F.Fab")
			(hide yes)
			(effects
				(font
					(size 1.016 1.016)
					(thickness 0.1524)
				)
			)
		)
		(duplicate_pad_numbers_are_jumpers no)
		(fp_rect
			(start -0.4318 0.9525)
			(end 0.4318 -0.9525)
			(stroke
				(width 0)
				(type default)
			)
			(fill no)
			(layer "F.CrtYd")
		)
		(fp_rect
			(start -0.4318 0.9525)
			(end 0.4318 -0.9525)
			(stroke
				(width 0)
				(type default)
			)
			(fill no)
			(layer "F.Fab")
		)
		(pad "1" smd custom
			(at 0 -0.4445 270)
			(size 0.1524 0.1524)
			(layers "F.Cu" "F.Mask" "F.Paste")
			(net "TPS74801_P1V2_STBY_OUT")
			(options
				(clearance outline)
				(anchor circle)
			)
			(primitives
				(gr_poly
					(pts
						(arc
							(start 0.3048 -0.2032)
							(mid 0.275042 -0.275042)
							(end 0.2032 -0.3048)
						)
						(arc
							(start -0.2032 -0.3048)
							(mid -0.275042 -0.275042)
							(end -0.3048 -0.2032)
						)
						(arc
							(start -0.3048 0.2032)
							(mid -0.275042 0.275042)
							(end -0.2032 0.3048)
						)
						(arc
							(start 0.2032 0.3048)
							(mid 0.275042 0.275042)
							(end 0.3048 0.2032)
						)
					)
					(width 0)
					(fill yes)
				)
			)
		)
		(pad "2" smd custom
			(at 0 0.4445 270)
			(size 0.1524 0.1524)
			(layers "F.Cu" "F.Mask" "F.Paste")
			(net "TPS74801_P1V2_STBY_FB")
			(options
				(clearance outline)
				(anchor circle)
			)
			(primitives
				(gr_poly
					(pts
						(arc
							(start 0.3048 -0.2032)
							(mid 0.275042 -0.275042)
							(end 0.2032 -0.3048)
						)
						(arc
							(start -0.2032 -0.3048)
							(mid -0.275042 -0.275042)
							(end -0.3048 -0.2032)
						)
						(arc
							(start -0.3048 0.2032)
							(mid -0.275042 0.275042)
							(end -0.2032 0.3048)
						)
						(arc
							(start 0.2032 0.3048)
							(mid 0.275042 0.275042)
							(end 0.3048 0.2032)
						)
					)
					(width 0)
					(fill yes)
				)
			)
		)
	)
)
